(kicad_pcb
	(version 20260206)
	(generator "pcbnew")
	(generator_version "10.0")
	(general
		(thickness 1.6)
		(legacy_teardrops no)
	)
	(paper "A4")
	(title_block
		(title "peb — Lightning_PEB_BRD.brd")
		(comment 1 "Lightning (Wiwynn / Facebook NVMe JBOF) / footprints 1360-1368 of 2563")
	)
	(layers
		(0 "F.Cu" signal "TOP")
		(4 "In1.Cu" signal "L2GND")
		(6 "In2.Cu" signal "L3")
		(8 "In3.Cu" signal "L4VCC")
		(10 "In4.Cu" signal "L5VCC")
		(12 "In5.Cu" signal "L6")
		(14 "In6.Cu" signal "L7GND")
		(2 "B.Cu" signal "BOTTOM")
		(9 "F.Adhes" user "F.Adhesive")
		(11 "B.Adhes" user "B.Adhesive")
		(13 "F.Paste" user "Package Geometry/Pastemask Top")
		(15 "B.Paste" user "Package Geometry/Pastemask Bottom")
		(5 "F.SilkS" user "Ref Des/Silkscreen Top")
		(7 "B.SilkS" user "Ref Des/Silkscreen Bottom")
		(1 "F.Mask" user "Board Geometry/Soldermask Top")
		(3 "B.Mask" user "Board Geometry/Soldermask Bottom")
		(17 "Dwgs.User" user "User.Drawings")
		(19 "Cmts.User" user "User.Comments")
		(21 "Eco1.User" user "User.Eco1")
		(23 "Eco2.User" user "User.Eco2")
		(25 "Edge.Cuts" user "Board Geometry/Outline")
		(27 "Margin" user)
		(31 "F.CrtYd" user "Package Geometry/Place Bound Top")
		(29 "B.CrtYd" user "Package Geometry/Place Bound Bottom")
		(35 "F.Fab" user "Ref Des/Assembly Top")
		(33 "B.Fab" user "Ref Des/Assembly Bottom")
	)
	(footprint ""
		(layer "F.Cu")
		(at 40.4114 -96.3168 -90)
		(property "Reference" "R50"
			(at 0 0 270)
			(layer "F.SilkS")
			(hide yes)
			(effects
				(font
					(size 1.27 1.27)
				)
			)
		)
		(property "Value" "0R2J-2-GP"
			(at 0.064008 -3.993896 270)
			(unlocked yes)
			(layer "F.Fab")
			(hide yes)
			(effects
				(font
					(size 1.016 1.016)
					(thickness 0.1524)
				)
			)
		)
		(property "Device Type" "R402H16"
			(at 0.064008 -5.517896 270)
			(unlocked yes)
			(layer "F.Fab")
			(hide yes)
			(effects
				(font
					(size 1.016 1.016)
					(thickness 0.1524)
				)
			)
		)
		(duplicate_pad_numbers_are_jumpers no)
		(fp_line
			(start -0.508 -0.9398)
			(end -0.508 0.9398)
			(stroke
				(width 0.1524)
				(type default)
			)
			(layer "F.SilkS")
		)
		(fp_line
			(start 0.508 -0.9398)
			(end -0.508 -0.9398)
			(stroke
				(width 0.1524)
				(type default)
			)
			(layer "F.SilkS")
		)
		(fp_rect
			(start -0.508 0.9398)
			(end 0.508 -0.9398)
			(stroke
				(width 0)
				(type default)
			)
			(fill no)
			(layer "F.CrtYd")
		)
		(fp_rect
			(start -0.508 0.9398)
			(end 0.508 -0.9398)
			(stroke
				(width 0)
				(type default)
			)
			(fill no)
			(layer "F.Fab")
		)
		(pad "1" smd custom
			(at 0 -0.4445 270)
			(size 0.1397 0.1397)
			(layers "F.Cu" "F.Mask" "F.Paste")
			(net "NVM_SI_R")
			(options
				(clearance outline)
				(anchor circle)
			)
			(primitives
				(gr_poly
					(pts
						(arc
							(start -0.1778 -0.2794)
							(mid -0.249642 -0.249642)
							(end -0.2794 -0.1778)
						)
						(arc
							(start -0.2794 0.1778)
							(mid -0.249642 0.249642)
							(end -0.1778 0.2794)
						)
						(arc
							(start 0.1778 0.2794)
							(mid 0.249642 0.249642)
							(end 0.2794 0.1778)
						)
						(arc
							(start 0.2794 -0.1778)
							(mid 0.249642 -0.249642)
							(end 0.1778 -0.2794)
						)
					)
					(width 0)
					(fill yes)
				)
			)
		)
		(pad "2" smd custom
			(at 0 0.4445 270)
			(size 0.1397 0.1397)
			(layers "F.Cu" "F.Mask" "F.Paste")
			(net "I2C_MUX_4A")
			(options
				(clearance outline)
				(anchor circle)
			)
			(primitives
				(gr_poly
					(pts
						(arc
							(start -0.1778 -0.2794)
							(mid -0.249642 -0.249642)
							(end -0.2794 -0.1778)
						)
						(arc
							(start -0.2794 0.1778)
							(mid -0.249642 0.249642)
							(end -0.1778 0.2794)
						)
						(arc
							(start 0.1778 0.2794)
							(mid 0.249642 0.249642)
							(end 0.2794 0.1778)
						)
						(arc
							(start 0.2794 -0.1778)
							(mid 0.249642 -0.249642)
							(end 0.1778 -0.2794)
						)
					)
					(width 0)
					(fill yes)
				)
			)
		)
	)
	(footprint ""
		(layer "F.Cu")
		(at 299.379894 -33.560258)
		(property "Reference" "C15"
			(at 0 0 0)
			(layer "F.SilkS")
			(hide yes)
			(effects
				(font
					(size 1.27 1.27)
				)
			)
		)
		(property "Value" "SCD22U10V2KX-1GP"
			(at 1.1811 -2.7051 0)
			(unlocked yes)
			(layer "F.Fab")
			(hide yes)
			(effects
				(font
					(size 1.016 1.016)
					(thickness 0.1524)
				)
			)
		)
		(property "Device Type" "C402H22"
			(at 1.1811 -4.2291 0)
			(unlocked yes)
			(layer "F.Fab")
			(hide yes)
			(effects
				(font
					(size 1.016 1.016)
					(thickness 0.1524)
				)
			)
		)
		(duplicate_pad_numbers_are_jumpers no)
		(fp_rect
			(start -0.4318 0.9525)
			(end 0.4318 -0.9525)
			(stroke
				(width 0)
				(type default)
			)
			(fill no)
			(layer "F.CrtYd")
		)
		(fp_rect
			(start -0.4318 0.9525)
			(end 0.4318 -0.9525)
			(stroke
				(width 0)
				(type default)
			)
			(fill no)
			(layer "F.Fab")
		)
		(pad "1" smd custom
			(at 0 -0.4445)
			(size 0.1524 0.1524)
			(layers "F.Cu" "F.Mask" "F.Paste")
			(net "PCIE_TX_CAP_P5")
			(options
				(clearance outline)
				(anchor circle)
			)
			(primitives
				(gr_poly
					(pts
						(arc
							(start 0.3048 -0.2032)
							(mid 0.275042 -0.275042)
							(end 0.2032 -0.3048)
						)
						(arc
							(start -0.2032 -0.3048)
							(mid -0.275042 -0.275042)
							(end -0.3048 -0.2032)
						)
						(arc
							(start -0.3048 0.2032)
							(mid -0.275042 0.275042)
							(end -0.2032 0.3048)
						)
						(arc
							(start 0.2032 0.3048)
							(mid 0.275042 0.275042)
							(end 0.3048 0.2032)
						)
					)
					(width 0)
					(fill yes)
				)
			)
		)
		(pad "2" smd custom
			(at 0 0.4445)
			(size 0.1524 0.1524)
			(layers "F.Cu" "F.Mask" "F.Paste")
			(net "PCIE_TX_P5")
			(options
				(clearance outline)
				(anchor circle)
			)
			(primitives
				(gr_poly
					(pts
						(arc
							(start 0.3048 -0.2032)
							(mid 0.275042 -0.275042)
							(end 0.2032 -0.3048)
						)
						(arc
							(start -0.2032 -0.3048)
							(mid -0.275042 -0.275042)
							(end -0.3048 -0.2032)
						)
						(arc
							(start -0.3048 0.2032)
							(mid -0.275042 0.275042)
							(end -0.2032 0.3048)
						)
						(arc
							(start 0.2032 0.3048)
							(mid 0.275042 0.275042)
							(end 0.3048 0.2032)
						)
					)
					(width 0)
					(fill yes)
				)
			)
		)
	)
	(footprint ""
		(layer "F.Cu")
		(at 314.833 -33.528)
		(property "Reference" "C23"
			(at 0 0 0)
			(layer "F.SilkS")
			(hide yes)
			(effects
				(font
					(size 1.27 1.27)
				)
			)
		)
		(property "Value" "SCD22U10V2KX-1GP"
			(at 1.1811 -2.7051 0)
			(unlocked yes)
			(layer "F.Fab")
			(hide yes)
			(effects
				(font
					(size 1.016 1.016)
					(thickness 0.1524)
				)
			)
		)
		(property "Device Type" "C402H22"
			(at 1.1811 -4.2291 0)
			(unlocked yes)
			(layer "F.Fab")
			(hide yes)
			(effects
				(font
					(size 1.016 1.016)
					(thickness 0.1524)
				)
			)
		)
		(duplicate_pad_numbers_are_jumpers no)
		(fp_rect
			(start -0.4318 0.9525)
			(end 0.4318 -0.9525)
			(stroke
				(width 0)
				(type default)
			)
			(fill no)
			(layer "F.CrtYd")
		)
		(fp_rect
			(start -0.4318 0.9525)
			(end 0.4318 -0.9525)
			(stroke
				(width 0)
				(type default)
			)
			(fill no)
			(layer "F.Fab")
		)
		(pad "1" smd custom
			(at 0 -0.4445)
			(size 0.1524 0.1524)
			(layers "F.Cu" "F.Mask" "F.Paste")
			(net "PCIE_TX_CAP_P11")
			(options
				(clearance outline)
				(anchor circle)
			)
			(primitives
				(gr_poly
					(pts
						(arc
							(start 0.3048 -0.2032)
							(mid 0.275042 -0.275042)
							(end 0.2032 -0.3048)
						)
						(arc
							(start -0.2032 -0.3048)
							(mid -0.275042 -0.275042)
							(end -0.3048 -0.2032)
						)
						(arc
							(start -0.3048 0.2032)
							(mid -0.275042 0.275042)
							(end -0.2032 0.3048)
						)
						(arc
							(start 0.2032 0.3048)
							(mid 0.275042 0.275042)
							(end 0.3048 0.2032)
						)
					)
					(width 0)
					(fill yes)
				)
			)
		)
		(pad "2" smd custom
			(at 0 0.4445)
			(size 0.1524 0.1524)
			(layers "F.Cu" "F.Mask" "F.Paste")
			(net "PCIE_TX_P11")
			(options
				(clearance outline)
				(anchor circle)
			)
			(primitives
				(gr_poly
					(pts
						(arc
							(start 0.3048 -0.2032)
							(mid 0.275042 -0.275042)
							(end 0.2032 -0.3048)
						)
						(arc
							(start -0.2032 -0.3048)
							(mid -0.275042 -0.275042)
							(end -0.3048 -0.2032)
						)
						(arc
							(start -0.3048 0.2032)
							(mid -0.275042 0.275042)
							(end -0.2032 0.3048)
						)
						(arc
							(start 0.2032 0.3048)
							(mid 0.275042 0.275042)
							(end 0.3048 0.2032)
						)
					)
					(width 0)
					(fill yes)
				)
			)
		)
	)
	(footprint ""
		(layer "F.Cu")
		(at 136.2583 -33.54324)
		(property "Reference" "C380"
			(at 0 0 0)
			(layer "F.SilkS")
			(hide yes)
			(effects
				(font
					(size 1.27 1.27)
				)
			)
		)
		(property "Value" "SCD22U10V2KX-1GP"
			(at 1.1811 -2.7051 0)
			(unlocked yes)
			(layer "F.Fab")
			(hide yes)
			(effects
				(font
					(size 1.016 1.016)
					(thickness 0.1524)
				)
			)
		)
		(property "Device Type" "C402H22"
			(at 1.1811 -4.2291 0)
			(unlocked yes)
			(layer "F.Fab")
			(hide yes)
			(effects
				(font
					(size 1.016 1.016)
					(thickness 0.1524)
				)
			)
		)
		(duplicate_pad_numbers_are_jumpers no)
		(fp_rect
			(start -0.4318 0.9525)
			(end 0.4318 -0.9525)
			(stroke
				(width 0)
				(type default)
			)
			(fill no)
			(layer "F.CrtYd")
		)
		(fp_rect
			(start -0.4318 0.9525)
			(end 0.4318 -0.9525)
			(stroke
				(width 0)
				(type default)
			)
			(fill no)
			(layer "F.Fab")
		)
		(pad "1" smd custom
			(at 0 -0.4445)
			(size 0.1524 0.1524)
			(layers "F.Cu" "F.Mask" "F.Paste")
			(net "PCIE_TX_CAP_N80")
			(options
				(clearance outline)
				(anchor circle)
			)
			(primitives
				(gr_poly
					(pts
						(arc
							(start 0.3048 -0.2032)
							(mid 0.275042 -0.275042)
							(end 0.2032 -0.3048)
						)
						(arc
							(start -0.2032 -0.3048)
							(mid -0.275042 -0.275042)
							(end -0.3048 -0.2032)
						)
						(arc
							(start -0.3048 0.2032)
							(mid -0.275042 0.275042)
							(end -0.2032 0.3048)
						)
						(arc
							(start 0.2032 0.3048)
							(mid 0.275042 0.275042)
							(end 0.3048 0.2032)
						)
					)
					(width 0)
					(fill yes)
				)
			)
		)
		(pad "2" smd custom
			(at 0 0.4445)
			(size 0.1524 0.1524)
			(layers "F.Cu" "F.Mask" "F.Paste")
			(net "PCIE_TX_N80")
			(options
				(clearance outline)
				(anchor circle)
			)
			(primitives
				(gr_poly
					(pts
						(arc
							(start 0.3048 -0.2032)
							(mid 0.275042 -0.275042)
							(end 0.2032 -0.3048)
						)
						(arc
							(start -0.2032 -0.3048)
							(mid -0.275042 -0.275042)
							(end -0.3048 -0.2032)
						)
						(arc
							(start -0.3048 0.2032)
							(mid -0.275042 0.275042)
							(end -0.2032 0.3048)
						)
						(arc
							(start 0.2032 0.3048)
							(mid 0.275042 0.275042)
							(end 0.3048 0.2032)
						)
					)
					(width 0)
					(fill yes)
				)
			)
		)
	)
	(footprint ""
		(layer "F.Cu")
		(at 182.8546 -71.628 180)
		(property "Reference" "C553"
			(at 0 0 180)
			(layer "F.SilkS")
			(hide yes)
			(effects
				(font
					(size 1.27 1.27)
				)
			)
		)
		(property "Value" "SC4D7U16V5KX-1-GP"
			(at -0.0762 -6.1214 180)
			(unlocked yes)
			(layer "F.Fab")
			(hide yes)
			(effects
				(font
					(size 1.016 1.016)
					(thickness 0.1524)
				)
			)
		)
		(property "Device Type" "C805H56"
			(at -0.0762 -8.1534 180)
			(unlocked yes)
			(layer "F.Fab")
			(hide yes)
			(effects
				(font
					(size 1.016 1.016)
					(thickness 0.1524)
				)
			)
		)
		(duplicate_pad_numbers_are_jumpers no)
		(fp_line
			(start 0.635 0)
			(end -0.635 0)
			(stroke
				(width 0.508)
				(type default)
			)
			(layer "F.SilkS")
		)
		(fp_rect
			(start -0.9652 1.778)
			(end 0.9652 -1.778)
			(stroke
				(width 0)
				(type default)
			)
			(fill no)
			(layer "F.CrtYd")
		)
		(fp_poly
			(pts
				(xy -0.9652 -1.778) (xy 0.9652 -1.778) (xy 0.9652 1.778) (xy -0.9652 1.778)
			)
			(stroke
				(width 0)
				(type default)
			)
			(fill no)
			(layer "F.Fab")
		)
		(pad "1" smd rect
			(at 0 -0.9652 180)
			(size 1.397 1.143)
			(layers "F.Cu" "F.Mask" "F.Paste")
			(net "DUT_AVD_PCIE")
		)
		(pad "2" smd rect
			(at 0 0.9652 180)
			(size 1.397 1.143)
			(layers "F.Cu" "F.Mask" "F.Paste")
			(net "GND")
		)
	)
	(footprint ""
		(layer "F.Cu")
		(at 51.816 -186.817)
		(property "Reference" "R903"
			(at 0 0 0)
			(layer "F.SilkS")
			(hide yes)
			(effects
				(font
					(size 1.27 1.27)
				)
			)
		)
		(property "Value" "0R2J-2-GP"
			(at 0.064008 -3.993896 0)
			(unlocked yes)
			(layer "F.Fab")
			(hide yes)
			(effects
				(font
					(size 1.016 1.016)
					(thickness 0.1524)
				)
			)
		)
		(property "Device Type" "R402H16"
			(at 0.064008 -5.517896 0)
			(unlocked yes)
			(layer "F.Fab")
			(hide yes)
			(effects
				(font
					(size 1.016 1.016)
					(thickness 0.1524)
				)
			)
		)
		(duplicate_pad_numbers_are_jumpers no)
		(fp_line
			(start -0.508 -0.9398)
			(end -0.508 0.9398)
			(stroke
				(width 0.1524)
				(type default)
			)
			(layer "F.SilkS")
		)
		(fp_line
			(start 0.508 -0.9398)
			(end -0.508 -0.9398)
			(stroke
				(width 0.1524)
				(type default)
			)
			(layer "F.SilkS")
		)
		(fp_rect
			(start -0.508 0.9398)
			(end 0.508 -0.9398)
			(stroke
				(width 0)
				(type default)
			)
			(fill no)
			(layer "F.CrtYd")
		)
		(fp_rect
			(start -0.508 0.9398)
			(end 0.508 -0.9398)
			(stroke
				(width 0)
				(type default)
			)
			(fill no)
			(layer "F.Fab")
		)
		(pad "1" smd custom
			(at 0 -0.4445)
			(size 0.1397 0.1397)
			(layers "F.Cu" "F.Mask" "F.Paste")
			(net "BUF_I2C8_CLKBUF1_SCL")
			(options
				(clearance outline)
				(anchor circle)
			)
			(primitives
				(gr_poly
					(pts
						(arc
							(start -0.1778 -0.2794)
							(mid -0.249642 -0.249642)
							(end -0.2794 -0.1778)
						)
						(arc
							(start -0.2794 0.1778)
							(mid -0.249642 0.249642)
							(end -0.1778 0.2794)
						)
						(arc
							(start 0.1778 0.2794)
							(mid 0.249642 0.249642)
							(end 0.2794 0.1778)
						)
						(arc
							(start 0.2794 -0.1778)
							(mid 0.249642 -0.249642)
							(end 0.1778 -0.2794)
						)
					)
					(width 0)
					(fill yes)
				)
			)
		)
		(pad "2" smd custom
			(at 0 0.4445)
			(size 0.1397 0.1397)
			(layers "F.Cu" "F.Mask" "F.Paste")
			(net "BUF_I2C8_CLKBUF1_SCL_R")
			(options
				(clearance outline)
				(anchor circle)
			)
			(primitives
				(gr_poly
					(pts
						(arc
							(start -0.1778 -0.2794)
							(mid -0.249642 -0.249642)
							(end -0.2794 -0.1778)
						)
						(arc
							(start -0.2794 0.1778)
							(mid -0.249642 0.249642)
							(end -0.1778 0.2794)
						)
						(arc
							(start 0.1778 0.2794)
							(mid 0.249642 0.249642)
							(end 0.2794 0.1778)
						)
						(arc
							(start 0.2794 -0.1778)
							(mid 0.249642 -0.249642)
							(end 0.1778 -0.2794)
						)
					)
					(width 0)
					(fill yes)
				)
			)
		)
	)
	(footprint ""
		(layer "F.Cu")
		(at 17.653 -109.347 90)
		(property "Reference" "PC77"
			(at 0 0 90)
			(layer "F.SilkS")
			(hide yes)
			(effects
				(font
					(size 1.27 1.27)
				)
			)
		)
		(property "Value" "SC4D7U16V5KX-1-GP"
			(at -0.0762 -6.1214 90)
			(unlocked yes)
			(layer "F.Fab")
			(hide yes)
			(effects
				(font
					(size 1.016 1.016)
					(thickness 0.1524)
				)
			)
		)
		(property "Device Type" "C805H56"
			(at -0.0762 -8.1534 90)
			(unlocked yes)
			(layer "F.Fab")
			(hide yes)
			(effects
				(font
					(size 1.016 1.016)
					(thickness 0.1524)
				)
			)
		)
		(duplicate_pad_numbers_are_jumpers no)
		(fp_line
			(start 0.635 0)
			(end -0.635 0)
			(stroke
				(width 0.508)
				(type default)
			)
			(layer "F.SilkS")
		)
		(fp_rect
			(start -0.9652 1.778)
			(end 0.9652 -1.778)
			(stroke
				(width 0)
				(type default)
			)
			(fill no)
			(layer "F.CrtYd")
		)
		(fp_poly
			(pts
				(xy -0.9652 -1.778) (xy 0.9652 -1.778) (xy 0.9652 1.778) (xy -0.9652 1.778)
			)
			(stroke
				(width 0)
				(type default)
			)
			(fill no)
			(layer "F.Fab")
		)
		(pad "1" smd rect
			(at 0 -0.9652 90)
			(size 1.397 1.143)
			(layers "F.Cu" "F.Mask" "F.Paste")
			(net "P1V26_PWR")
		)
		(pad "2" smd rect
			(at 0 0.9652 90)
			(size 1.397 1.143)
			(layers "F.Cu" "F.Mask" "F.Paste")
			(net "GND")
		)
	)
	(footprint ""
		(layer "F.Cu")
		(at 190.052198 -51.356768)
		(property "Reference" "C518"
			(at 0 0 0)
			(layer "F.SilkS")
			(hide yes)
			(effects
				(font
					(size 1.27 1.27)
				)
			)
		)
		(property "Value" "SC47U4V5MX-2-GP"
			(at -0.0762 -6.1214 0)
			(unlocked yes)
			(layer "F.Fab")
			(hide yes)
			(effects
				(font
					(size 1.016 1.016)
					(thickness 0.1524)
				)
			)
		)
		(property "Device Type" "C805H58"
			(at -0.0762 -8.1534 0)
			(unlocked yes)
			(layer "F.Fab")
			(hide yes)
			(effects
				(font
					(size 1.016 1.016)
					(thickness 0.1524)
				)
			)
		)
		(duplicate_pad_numbers_are_jumpers no)
		(fp_line
			(start 0.635 0)
			(end -0.635 0)
			(stroke
				(width 0.508)
				(type default)
			)
			(layer "F.SilkS")
		)
		(fp_rect
			(start -0.9652 1.778)
			(end 0.9652 -1.778)
			(stroke
				(width 0)
				(type default)
			)
			(fill no)
			(layer "F.CrtYd")
		)
		(fp_poly
			(pts
				(xy -0.9652 -1.778) (xy 0.9652 -1.778) (xy 0.9652 1.778) (xy -0.9652 1.778)
			)
			(stroke
				(width 0)
				(type default)
			)
			(fill no)
			(layer "F.Fab")
		)
		(pad "1" smd rect
			(at 0 -0.9652)
			(size 1.397 1.143)
			(layers "F.Cu" "F.Mask" "F.Paste")
			(net "DUT_AVD_PCIE_Q")
		)
		(pad "2" smd rect
			(at 0 0.9652)
			(size 1.397 1.143)
			(layers "F.Cu" "F.Mask" "F.Paste")
			(net "GND")
		)
	)
	(footprint ""
		(layer "F.Cu")
		(at 42.545 -198.882 90)
		(property "Reference" "C698"
			(at 0 0 90)
			(layer "F.SilkS")
			(hide yes)
			(effects
				(font
					(size 1.27 1.27)
				)
			)
		)
		(property "Value" "SC220P50V3JN-GP"
			(at 0 -2.8194 90)
			(unlocked yes)
			(layer "F.Fab")
			(hide yes)
			(effects
				(font
					(size 1.016 1.016)
					(thickness 0.1524)
				)
			)
		)
		(property "Device Type" "C603H36"
			(at 0 -4.3434 90)
			(unlocked yes)
			(layer "F.Fab")
			(hide yes)
			(effects
				(font
					(size 1.016 1.016)
					(thickness 0.1524)
				)
			)
		)
		(duplicate_pad_numbers_are_jumpers no)
		(fp_line
			(start 0.508 0)
			(end -0.508 0)
			(stroke
				(width 0.2032)
				(type default)
			)
			(layer "F.SilkS")
		)
		(fp_rect
			(start -0.5842 1.3335)
			(end 0.5842 -1.3335)
			(stroke
				(width 0)
				(type default)
			)
			(fill no)
			(layer "F.CrtYd")
		)
		(fp_rect
			(start -0.5842 1.3335)
			(end 0.5842 -1.3335)
			(stroke
				(width 0)
				(type default)
			)
			(fill no)
			(layer "F.Fab")
		)
		(pad "1" smd custom
			(at 0 -0.762 90)
			(size 0.2159 0.2159)
			(layers "F.Cu" "F.Mask" "F.Paste")
			(net "BMC_I2C6_C_FCB_SCL_R")
			(options
				(clearance outline)
				(anchor circle)
			)
			(primitives
				(gr_poly
					(pts
						(arc
							(start -0.3302 -0.4318)
							(mid -0.402042 -0.402042)
							(end -0.4318 -0.3302)
						)
						(arc
							(start -0.4318 0.3302)
							(mid -0.402042 0.402042)
							(end -0.3302 0.4318)
						)
						(arc
							(start 0.3302 0.4318)
							(mid 0.402042 0.402042)
							(end 0.4318 0.3302)
						)
						(arc
							(start 0.4318 -0.3302)
							(mid 0.402042 -0.402042)
							(end 0.3302 -0.4318)
						)
					)
					(width 0)
					(fill yes)
				)
			)
		)
		(pad "2" smd custom
			(at 0 0.762 90)
			(size 0.2159 0.2159)
			(layers "F.Cu" "F.Mask" "F.Paste")
			(net "GND")
			(options
				(clearance outline)
				(anchor circle)
			)
			(primitives
				(gr_poly
					(pts
						(arc
							(start -0.3302 -0.4318)
							(mid -0.402042 -0.402042)
							(end -0.4318 -0.3302)
						)
						(arc
							(start -0.4318 0.3302)
							(mid -0.402042 0.402042)
							(end -0.3302 0.4318)
						)
						(arc
							(start 0.3302 0.4318)
							(mid 0.402042 0.402042)
							(end 0.4318 0.3302)
						)
						(arc
							(start 0.4318 -0.3302)
							(mid 0.402042 -0.402042)
							(end 0.3302 -0.4318)
						)
					)
					(width 0)
					(fill yes)
				)
			)
		)
	)
)
